(kicad_pcb
	(version 20260206)
	(generator "pcbnew")
	(generator_version "10.0")
	(general
		(thickness 1.6)
		(legacy_teardrops no)
	)
	(paper "A4")
	(title_block
		(title "Bryce Canyon_F.DPB_16315-1-OCP.brd")
		(comment 1 "Bryce Canyon / footprint 1370 of 2223 (MONO1), pads 1-73 of 166")
	)
	(layers
		(0 "F.Cu" signal "TOP")
		(4 "In1.Cu" signal "L2GND")
		(6 "In2.Cu" signal "L3")
		(8 "In3.Cu" signal "L4GND")
		(10 "In4.Cu" signal "L5")
		(12 "In5.Cu" signal "L6VCC")
		(14 "In6.Cu" signal "L7VCC")
		(16 "In7.Cu" signal "L8")
		(18 "In8.Cu" signal "L9GND")
		(20 "In9.Cu" signal "L10")
		(22 "In10.Cu" signal "L11GND")
		(2 "B.Cu" signal "BOTTOM")
		(9 "F.Adhes" user "F.Adhesive")
		(11 "B.Adhes" user "B.Adhesive")
		(13 "F.Paste" user "Package Geometry/Pastemask Top")
		(15 "B.Paste" user "Package Geometry/Pastemask Bottom")
		(5 "F.SilkS" user "Ref Des/Silkscreen Top")
		(7 "B.SilkS" user "Ref Des/Silkscreen Bottom")
		(1 "F.Mask" user "Board Geometry/Soldermask Top")
		(3 "B.Mask" user "Board Geometry/Soldermask Bottom")
		(17 "Dwgs.User" user "User.Drawings")
		(19 "Cmts.User" user "User.Comments")
		(21 "Eco1.User" user "User.Eco1")
		(23 "Eco2.User" user "User.Eco2")
		(25 "Edge.Cuts" user "Board Geometry/Outline")
		(27 "Margin" user)
		(31 "F.CrtYd" user "Package Geometry/Place Bound Top")
		(29 "B.CrtYd" user "Package Geometry/Place Bound Bottom")
		(35 "F.Fab" user "Ref Des/Assembly Top")
		(33 "B.Fab" user "Ref Des/Assembly Bottom")
	)
	(footprint ""
		(layer "F.Cu")
		(at 239.300004 -111.149892 90)
		(property "Reference" "MONO1"
			(at 0 0 90)
			(layer "F.SilkS")
			(hide yes)
			(effects
				(font
					(size 1.27 1.27)
				)
			)
		)
		(property "Value" "AMP-CONN164-4R-1-GP"
			(at -25.705054 -1.203706 90)
			(unlocked yes)
			(layer "F.Fab")
			(hide yes)
			(effects
				(font
					(size 1.016 1.016)
					(thickness 0.1524)
				)
			)
		)
		(property "Device Type" "PREFIT-164P-890091-1H441"
			(at -25.705054 -2.727706 90)
			(unlocked yes)
			(layer "F.Fab")
			(hide yes)
			(effects
				(font
					(size 1.016 1.016)
					(thickness 0.1524)
				)
			)
		)
		(duplicate_pad_numbers_are_jumpers no)
		(pad "" np_thru_hole circle
			(at 0 0 90)
			(size 0.254 0.254)
			(drill 2.3622)
			(layers "*.Cu" "*.Mask")
			(clearance 1.4097)
			(thermal_gap 1.4097)
		)
		(pad "" np_thru_hole circle
			(at 73.149968 0 90)
			(size 0.254 0.254)
			(drill 2.3622)
			(layers "*.Cu" "*.Mask")
			(clearance 1.4097)
			(thermal_gap 1.4097)
		)
		(pad "A1" thru_hole circle
			(at -11.649964 -1.249934 90)
			(size 1.0668 1.0668)
			(drill 0.719836)
			(layers "*.Cu" "*.Mask")
			(remove_unused_layers no)
			(net "COMP_A_PRI_INS_N")
			(clearance 0.1905)
			(thermal_gap 0.1905)
		)
		(pad "A2" thru_hole circle
			(at -10.649966 -3.24993 90)
			(size 1.0668 1.0668)
			(drill 0.719836)
			(layers "*.Cu" "*.Mask")
			(remove_unused_layers no)
			(net "P12V_A_COMP")
			(clearance 0.1905)
			(thermal_gap 0.1905)
		)
		(pad "A3" thru_hole circle
			(at -9.649968 -1.249934 90)
			(size 1.0668 1.0668)
			(drill 0.719836)
			(layers "*.Cu" "*.Mask")
			(remove_unused_layers no)
			(net "P12V_A_COMP")
			(clearance 0.1905)
			(thermal_gap 0.1905)
		)
		(pad "A4" thru_hole circle
			(at -8.64997 -3.24993 90)
			(size 1.0668 1.0668)
			(drill 0.719836)
			(layers "*.Cu" "*.Mask")
			(remove_unused_layers no)
			(net "GND")
			(clearance 0.1905)
			(thermal_gap 0.1905)
		)
		(pad "A5" thru_hole circle
			(at -7.649972 -1.249934 90)
			(size 1.0668 1.0668)
			(drill 0.719836)
			(layers "*.Cu" "*.Mask")
			(remove_unused_layers no)
			(net "SLOT3_SVR_ID0_GPIO0")
			(clearance 0.1905)
			(thermal_gap 0.1905)
		)
		(pad "A6" thru_hole circle
			(at -6.649974 -3.24993 90)
			(size 1.0668 1.0668)
			(drill 0.719836)
			(layers "*.Cu" "*.Mask")
			(remove_unused_layers no)
			(net "SLOT3_SVR_ID0_GPIO1")
			(clearance 0.1905)
			(thermal_gap 0.1905)
		)
		(pad "A7" thru_hole circle
			(at -5.649976 -1.249934 90)
			(size 1.0668 1.0668)
			(drill 0.719836)
			(layers "*.Cu" "*.Mask")
			(remove_unused_layers no)
			(net "UART_COMP_A_TX")
			(clearance 0.1905)
			(thermal_gap 0.1905)
		)
		(pad "A8" thru_hole circle
			(at -4.649978 -3.24993 90)
			(size 1.0668 1.0668)
			(drill 0.719836)
			(layers "*.Cu" "*.Mask")
			(remove_unused_layers no)
			(net "UART_COMP_A_RX")
			(clearance 0.1905)
			(thermal_gap 0.1905)
		)
		(pad "A9" thru_hole circle
			(at -3.64998 -1.249934 90)
			(size 1.0668 1.0668)
			(drill 0.719836)
			(layers "*.Cu" "*.Mask")
			(remove_unused_layers no)
			(net "SLOT3_SVR_ID0_GPIO2")
			(clearance 0.1905)
			(thermal_gap 0.1905)
		)
		(pad "A10" thru_hole circle
			(at -2.649982 -3.24993 90)
			(size 1.0668 1.0668)
			(drill 0.719836)
			(layers "*.Cu" "*.Mask")
			(remove_unused_layers no)
			(net "SLOT3_SVR_ID0_GPIO3")
			(clearance 0.1905)
			(thermal_gap 0.1905)
		)
		(pad "A11" thru_hole circle
			(at -1.649984 -1.249934 90)
			(size 1.0668 1.0668)
			(drill 0.719836)
			(layers "*.Cu" "*.Mask")
			(remove_unused_layers no)
			(net "PCIE_COMP_A_TO_SCC_A_RST_0")
			(clearance 0.1905)
			(thermal_gap 0.1905)
		)
		(pad "A12" thru_hole circle
			(at 1.35001 -3.24993 90)
			(size 1.0668 1.0668)
			(drill 0.719836)
			(layers "*.Cu" "*.Mask")
			(remove_unused_layers no)
			(net "GND")
			(clearance 0.1905)
			(thermal_gap 0.1905)
		)
		(pad "A13" thru_hole circle
			(at 2.350008 -1.249934 90)
			(size 1.0668 1.0668)
			(drill 0.719836)
			(layers "*.Cu" "*.Mask")
			(remove_unused_layers no)
			(net "PCIE_COMP_A_TO_SCC_A_CLK_0_DP")
			(clearance 0.1905)
			(thermal_gap 0.1905)
		)
		(pad "A14" thru_hole circle
			(at 3.350006 -3.24993 90)
			(size 1.0668 1.0668)
			(drill 0.719836)
			(layers "*.Cu" "*.Mask")
			(remove_unused_layers no)
			(net "PCIE_COMP_A_TO_SCC_A_CLK_0_DN")
			(clearance 0.1905)
			(thermal_gap 0.1905)
		)
		(pad "A15" thru_hole circle
			(at 4.350004 -1.249934 90)
			(size 1.0668 1.0668)
			(drill 0.719836)
			(layers "*.Cu" "*.Mask")
			(remove_unused_layers no)
			(net "GND")
			(clearance 0.1905)
			(thermal_gap 0.1905)
		)
		(pad "A16" thru_hole circle
			(at 5.350002 -3.24993 90)
			(size 1.0668 1.0668)
			(drill 0.719836)
			(layers "*.Cu" "*.Mask")
			(remove_unused_layers no)
			(net "GND")
			(clearance 0.1905)
			(thermal_gap 0.1905)
		)
		(pad "A17" thru_hole circle
			(at 6.35 -1.249934 90)
			(size 1.0668 1.0668)
			(drill 0.719836)
			(layers "*.Cu" "*.Mask")
			(remove_unused_layers no)
			(net "PCIE_SCC_A_TO_COMP_A_0_DP")
			(clearance 0.1905)
			(thermal_gap 0.1905)
		)
		(pad "A18" thru_hole circle
			(at 7.349998 -3.24993 90)
			(size 1.0668 1.0668)
			(drill 0.719836)
			(layers "*.Cu" "*.Mask")
			(remove_unused_layers no)
			(net "PCIE_SCC_A_TO_COMP_A_0_DN")
			(clearance 0.1905)
			(thermal_gap 0.1905)
		)
		(pad "A19" thru_hole circle
			(at 8.349996 -1.249934 90)
			(size 1.0668 1.0668)
			(drill 0.719836)
			(layers "*.Cu" "*.Mask")
			(remove_unused_layers no)
			(net "GND")
			(clearance 0.1905)
			(thermal_gap 0.1905)
		)
		(pad "A20" thru_hole circle
			(at 9.349994 -3.24993 90)
			(size 1.0668 1.0668)
			(drill 0.719836)
			(layers "*.Cu" "*.Mask")
			(remove_unused_layers no)
			(net "GND")
			(clearance 0.1905)
			(thermal_gap 0.1905)
		)
		(pad "A21" thru_hole circle
			(at 10.349992 -1.249934 90)
			(size 1.0668 1.0668)
			(drill 0.719836)
			(layers "*.Cu" "*.Mask")
			(remove_unused_layers no)
			(net "PCIE_SCC_A_TO_COMP_A_1_DP")
			(clearance 0.1905)
			(thermal_gap 0.1905)
		)
		(pad "A22" thru_hole circle
			(at 11.34999 -3.24993 90)
			(size 1.0668 1.0668)
			(drill 0.719836)
			(layers "*.Cu" "*.Mask")
			(remove_unused_layers no)
			(net "PCIE_SCC_A_TO_COMP_A_1_DN")
			(clearance 0.1905)
			(thermal_gap 0.1905)
		)
		(pad "A23" thru_hole circle
			(at 12.349988 -1.249934 90)
			(size 1.0668 1.0668)
			(drill 0.719836)
			(layers "*.Cu" "*.Mask")
			(remove_unused_layers no)
			(net "GND")
			(clearance 0.1905)
			(thermal_gap 0.1905)
		)
		(pad "A24" thru_hole circle
			(at 13.349986 -3.24993 90)
			(size 1.0668 1.0668)
			(drill 0.719836)
			(layers "*.Cu" "*.Mask")
			(remove_unused_layers no)
			(net "GND")
			(clearance 0.1905)
			(thermal_gap 0.1905)
		)
		(pad "A25" thru_hole circle
			(at 14.349984 -1.249934 90)
			(size 1.0668 1.0668)
			(drill 0.719836)
			(layers "*.Cu" "*.Mask")
			(remove_unused_layers no)
			(net "PCIE_SCC_A_TO_COMP_A_2_DP")
			(clearance 0.1905)
			(thermal_gap 0.1905)
		)
		(pad "A26" thru_hole circle
			(at 15.349982 -3.24993 90)
			(size 1.0668 1.0668)
			(drill 0.719836)
			(layers "*.Cu" "*.Mask")
			(remove_unused_layers no)
			(net "PCIE_SCC_A_TO_COMP_A_2_DN")
			(clearance 0.1905)
			(thermal_gap 0.1905)
		)
		(pad "A27" thru_hole circle
			(at 16.34998 -1.249934 90)
			(size 1.0668 1.0668)
			(drill 0.719836)
			(layers "*.Cu" "*.Mask")
			(remove_unused_layers no)
			(net "GND")
			(clearance 0.1905)
			(thermal_gap 0.1905)
		)
		(pad "A28" thru_hole circle
			(at 17.349978 -3.24993 90)
			(size 1.0668 1.0668)
			(drill 0.719836)
			(layers "*.Cu" "*.Mask")
			(remove_unused_layers no)
			(net "GND")
			(clearance 0.1905)
			(thermal_gap 0.1905)
		)
		(pad "A29" thru_hole circle
			(at 18.349976 -1.249934 90)
			(size 1.0668 1.0668)
			(drill 0.719836)
			(layers "*.Cu" "*.Mask")
			(remove_unused_layers no)
			(net "PCIE_SCC_A_TO_COMP_A_3_DP")
			(clearance 0.1905)
			(thermal_gap 0.1905)
		)
		(pad "A30" thru_hole circle
			(at 19.349974 -3.24993 90)
			(size 1.0668 1.0668)
			(drill 0.719836)
			(layers "*.Cu" "*.Mask")
			(remove_unused_layers no)
			(net "PCIE_SCC_A_TO_COMP_A_3_DN")
			(clearance 0.1905)
			(thermal_gap 0.1905)
		)
		(pad "A31" thru_hole circle
			(at 20.349972 -1.249934 90)
			(size 1.0668 1.0668)
			(drill 0.719836)
			(layers "*.Cu" "*.Mask")
			(remove_unused_layers no)
			(net "GND")
			(clearance 0.1905)
			(thermal_gap 0.1905)
		)
		(pad "A32" thru_hole circle
			(at 21.34997 -3.24993 90)
			(size 1.0668 1.0668)
			(drill 0.719836)
			(layers "*.Cu" "*.Mask")
			(remove_unused_layers no)
			(net "GND")
			(clearance 0.1905)
			(thermal_gap 0.1905)
		)
		(pad "A33" thru_hole circle
			(at 22.349968 -1.249934 90)
			(size 1.0668 1.0668)
			(drill 0.719836)
			(layers "*.Cu" "*.Mask")
			(remove_unused_layers no)
			(net "TP_COMP_A_SATA_P0_RX_DP")
			(clearance 0.1905)
			(thermal_gap 0.1905)
		)
		(pad "A34" thru_hole circle
			(at 23.349966 -3.24993 90)
			(size 1.0668 1.0668)
			(drill 0.719836)
			(layers "*.Cu" "*.Mask")
			(remove_unused_layers no)
			(net "TP_COMP_A_SATA_P0_RX_DN")
			(clearance 0.1905)
			(thermal_gap 0.1905)
		)
		(pad "A35" thru_hole circle
			(at 24.349964 -1.249934 90)
			(size 1.0668 1.0668)
			(drill 0.719836)
			(layers "*.Cu" "*.Mask")
			(remove_unused_layers no)
			(net "GND")
			(clearance 0.1905)
			(thermal_gap 0.1905)
		)
		(pad "A36" thru_hole circle
			(at 25.349962 -3.24993 90)
			(size 1.0668 1.0668)
			(drill 0.719836)
			(layers "*.Cu" "*.Mask")
			(remove_unused_layers no)
			(net "GND")
			(clearance 0.1905)
			(thermal_gap 0.1905)
		)
		(pad "A37" thru_hole circle
			(at 26.34996 -1.249934 90)
			(size 1.0668 1.0668)
			(drill 0.719836)
			(layers "*.Cu" "*.Mask")
			(remove_unused_layers no)
			(net "PCIE_COMP_A_TO_IOM_A_CLK_2_DP")
			(clearance 0.1905)
			(thermal_gap 0.1905)
		)
		(pad "A38" thru_hole circle
			(at 27.349958 -3.24993 90)
			(size 1.0668 1.0668)
			(drill 0.719836)
			(layers "*.Cu" "*.Mask")
			(remove_unused_layers no)
			(net "PCIE_COMP_A_TO_IOM_A_CLK_2_DN")
			(clearance 0.1905)
			(thermal_gap 0.1905)
		)
		(pad "A39" thru_hole circle
			(at 28.349956 -1.249934 90)
			(size 1.0668 1.0668)
			(drill 0.719836)
			(layers "*.Cu" "*.Mask")
			(remove_unused_layers no)
			(net "GND")
			(clearance 0.1905)
			(thermal_gap 0.1905)
		)
		(pad "A40" thru_hole circle
			(at 29.349954 -3.24993 90)
			(size 1.0668 1.0668)
			(drill 0.719836)
			(layers "*.Cu" "*.Mask")
			(remove_unused_layers no)
			(net "GND")
			(clearance 0.1905)
			(thermal_gap 0.1905)
		)
		(pad "A41" thru_hole circle
			(at 30.349952 -1.249934 90)
			(size 1.0668 1.0668)
			(drill 0.719836)
			(layers "*.Cu" "*.Mask")
			(remove_unused_layers no)
			(net "COMP_A_FAST_THROTTLE_N")
			(clearance 0.1905)
			(thermal_gap 0.1905)
		)
		(pad "A42" thru_hole circle
			(at 31.34995 -3.24993 90)
			(size 1.0668 1.0668)
			(drill 0.719836)
			(layers "*.Cu" "*.Mask")
			(remove_unused_layers no)
			(net "TP_SMB_COMP_A_NIC_ALERT_N")
			(clearance 0.1905)
			(thermal_gap 0.1905)
		)
		(pad "A43" thru_hole circle
			(at 32.349948 -1.249934 90)
			(size 1.0668 1.0668)
			(drill 0.719836)
			(layers "*.Cu" "*.Mask")
			(remove_unused_layers no)
			(net "GND")
			(clearance 0.1905)
			(thermal_gap 0.1905)
		)
		(pad "A44" thru_hole circle
			(at 33.349946 -3.24993 90)
			(size 1.0668 1.0668)
			(drill 0.719836)
			(layers "*.Cu" "*.Mask")
			(remove_unused_layers no)
			(net "GND")
			(clearance 0.1905)
			(thermal_gap 0.1905)
		)
		(pad "A45" thru_hole circle
			(at 34.349944 -1.249934 90)
			(size 1.0668 1.0668)
			(drill 0.719836)
			(layers "*.Cu" "*.Mask")
			(remove_unused_layers no)
			(net "TP_COMP_A_KR_P0_RX_DP")
			(clearance 0.1905)
			(thermal_gap 0.1905)
		)
		(pad "A46" thru_hole circle
			(at 35.349942 -3.24993 90)
			(size 1.0668 1.0668)
			(drill 0.719836)
			(layers "*.Cu" "*.Mask")
			(remove_unused_layers no)
			(net "TP_COMP_A_KR_P0_RX_DN")
			(clearance 0.1905)
			(thermal_gap 0.1905)
		)
		(pad "A47" thru_hole circle
			(at 36.34994 -1.249934 90)
			(size 1.0668 1.0668)
			(drill 0.719836)
			(layers "*.Cu" "*.Mask")
			(remove_unused_layers no)
			(net "GND")
			(clearance 0.1905)
			(thermal_gap 0.1905)
		)
		(pad "A48" thru_hole circle
			(at 37.349938 -3.24993 90)
			(size 1.0668 1.0668)
			(drill 0.719836)
			(layers "*.Cu" "*.Mask")
			(remove_unused_layers no)
			(net "GND")
			(clearance 0.1905)
			(thermal_gap 0.1905)
		)
		(pad "A49" thru_hole circle
			(at 38.349936 -1.249934 90)
			(size 1.0668 1.0668)
			(drill 0.719836)
			(layers "*.Cu" "*.Mask")
			(remove_unused_layers no)
			(net "PCIE_SCC_A_TO_COMP_A_4_DP")
			(clearance 0.1905)
			(thermal_gap 0.1905)
		)
		(pad "A50" thru_hole circle
			(at 39.349934 -3.24993 90)
			(size 1.0668 1.0668)
			(drill 0.719836)
			(layers "*.Cu" "*.Mask")
			(remove_unused_layers no)
			(net "PCIE_SCC_A_TO_COMP_A_4_DN")
			(clearance 0.1905)
			(thermal_gap 0.1905)
		)
		(pad "A51" thru_hole circle
			(at 40.349932 -1.249934 90)
			(size 1.0668 1.0668)
			(drill 0.719836)
			(layers "*.Cu" "*.Mask")
			(remove_unused_layers no)
			(net "GND")
			(clearance 0.1905)
			(thermal_gap 0.1905)
		)
		(pad "A52" thru_hole circle
			(at 41.34993 -3.24993 90)
			(size 1.0668 1.0668)
			(drill 0.719836)
			(layers "*.Cu" "*.Mask")
			(remove_unused_layers no)
			(net "GND")
			(clearance 0.1905)
			(thermal_gap 0.1905)
		)
		(pad "A53" thru_hole circle
			(at 42.349928 -1.249934 90)
			(size 1.0668 1.0668)
			(drill 0.719836)
			(layers "*.Cu" "*.Mask")
			(remove_unused_layers no)
			(net "PCIE_SCC_A_TO_COMP_A_5_DP")
			(clearance 0.1905)
			(thermal_gap 0.1905)
		)
		(pad "A54" thru_hole circle
			(at 43.349926 -3.24993 90)
			(size 1.0668 1.0668)
			(drill 0.719836)
			(layers "*.Cu" "*.Mask")
			(remove_unused_layers no)
			(net "PCIE_SCC_A_TO_COMP_A_5_DN")
			(clearance 0.1905)
			(thermal_gap 0.1905)
		)
		(pad "A55" thru_hole circle
			(at 44.349924 -1.249934 90)
			(size 1.0668 1.0668)
			(drill 0.719836)
			(layers "*.Cu" "*.Mask")
			(remove_unused_layers no)
			(net "GND")
			(clearance 0.1905)
			(thermal_gap 0.1905)
		)
		(pad "A56" thru_hole circle
			(at 45.349922 -3.24993 90)
			(size 1.0668 1.0668)
			(drill 0.719836)
			(layers "*.Cu" "*.Mask")
			(remove_unused_layers no)
			(net "GND")
			(clearance 0.1905)
			(thermal_gap 0.1905)
		)
		(pad "A57" thru_hole circle
			(at 46.34992 -1.249934 90)
			(size 1.0668 1.0668)
			(drill 0.719836)
			(layers "*.Cu" "*.Mask")
			(remove_unused_layers no)
			(net "PCIE_SCC_A_TO_COMP_A_6_DP")
			(clearance 0.1905)
			(thermal_gap 0.1905)
		)
		(pad "A58" thru_hole circle
			(at 47.349918 -3.24993 90)
			(size 1.0668 1.0668)
			(drill 0.719836)
			(layers "*.Cu" "*.Mask")
			(remove_unused_layers no)
			(net "PCIE_SCC_A_TO_COMP_A_6_DN")
			(clearance 0.1905)
			(thermal_gap 0.1905)
		)
		(pad "A59" thru_hole circle
			(at 48.349916 -1.249934 90)
			(size 1.0668 1.0668)
			(drill 0.719836)
			(layers "*.Cu" "*.Mask")
			(remove_unused_layers no)
			(net "GND")
			(clearance 0.1905)
			(thermal_gap 0.1905)
		)
		(pad "A60" thru_hole circle
			(at 49.349914 -3.24993 90)
			(size 1.0668 1.0668)
			(drill 0.719836)
			(layers "*.Cu" "*.Mask")
			(remove_unused_layers no)
			(net "GND")
			(clearance 0.1905)
			(thermal_gap 0.1905)
		)
		(pad "A61" thru_hole circle
			(at 50.349912 -1.249934 90)
			(size 1.0668 1.0668)
			(drill 0.719836)
			(layers "*.Cu" "*.Mask")
			(remove_unused_layers no)
			(net "PCIE_SCC_A_TO_COMP_A_7_DP")
			(clearance 0.1905)
			(thermal_gap 0.1905)
		)
		(pad "A62" thru_hole circle
			(at 51.34991 -3.24993 90)
			(size 1.0668 1.0668)
			(drill 0.719836)
			(layers "*.Cu" "*.Mask")
			(remove_unused_layers no)
			(net "PCIE_SCC_A_TO_COMP_A_7_DN")
			(clearance 0.1905)
			(thermal_gap 0.1905)
		)
		(pad "A63" thru_hole circle
			(at 52.349908 -1.249934 90)
			(size 1.0668 1.0668)
			(drill 0.719836)
			(layers "*.Cu" "*.Mask")
			(remove_unused_layers no)
			(net "GND")
			(clearance 0.1905)
			(thermal_gap 0.1905)
		)
		(pad "A64" thru_hole circle
			(at 53.349906 -3.24993 90)
			(size 1.0668 1.0668)
			(drill 0.719836)
			(layers "*.Cu" "*.Mask")
			(remove_unused_layers no)
			(net "GND")
			(clearance 0.1905)
			(thermal_gap 0.1905)
		)
		(pad "A65" thru_hole circle
			(at 54.349904 -1.249934 90)
			(size 1.0668 1.0668)
			(drill 0.719836)
			(layers "*.Cu" "*.Mask")
			(remove_unused_layers no)
			(net "PCIE_IOM_A_TO_COMP_A_8_DP")
			(clearance 0.1905)
			(thermal_gap 0.1905)
		)
		(pad "A66" thru_hole circle
			(at 55.349902 -3.24993 90)
			(size 1.0668 1.0668)
			(drill 0.719836)
			(layers "*.Cu" "*.Mask")
			(remove_unused_layers no)
			(net "PCIE_IOM_A_TO_COMP_A_8_DN")
			(clearance 0.1905)
			(thermal_gap 0.1905)
		)
		(pad "A67" thru_hole circle
			(at 56.3499 -1.249934 90)
			(size 1.0668 1.0668)
			(drill 0.719836)
			(layers "*.Cu" "*.Mask")
			(remove_unused_layers no)
			(net "GND")
			(clearance 0.1905)
			(thermal_gap 0.1905)
		)
		(pad "A68" thru_hole circle
			(at 57.349898 -3.24993 90)
			(size 1.0668 1.0668)
			(drill 0.719836)
			(layers "*.Cu" "*.Mask")
			(remove_unused_layers no)
			(net "GND")
			(clearance 0.1905)
			(thermal_gap 0.1905)
		)
		(pad "A69" thru_hole circle
			(at 58.349896 -1.249934 90)
			(size 1.0668 1.0668)
			(drill 0.719836)
			(layers "*.Cu" "*.Mask")
			(remove_unused_layers no)
			(net "PCIE_IOM_A_TO_COMP_A_9_DP")
			(clearance 0.1905)
			(thermal_gap 0.1905)
		)
		(pad "A70" thru_hole circle
			(at 59.349894 -3.24993 90)
			(size 1.0668 1.0668)
			(drill 0.719836)
			(layers "*.Cu" "*.Mask")
			(remove_unused_layers no)
			(net "PCIE_IOM_A_TO_COMP_A_9_DN")
			(clearance 0.1905)
			(thermal_gap 0.1905)
		)
		(pad "A71" thru_hole circle
			(at 60.349892 -1.249934 90)
			(size 1.0668 1.0668)
			(drill 0.719836)
			(layers "*.Cu" "*.Mask")
			(remove_unused_layers no)
			(net "GND")
			(clearance 0.1905)
			(thermal_gap 0.1905)
		)
	)
)
